# S9S_MB_2U (Grand Teton) — schematic netlist excerpt (pin names and nets, part order shuffled) for the footprints in the layout excerpt that follows; sources: Cadence DE-HDL packaged netlist, KiCad conversion of 03242023_DA0F0TMBIJ0_F0T_Motherboard_J_brd_V01_OCP.brd

R555  Q_RES  100 1% CHIP  pkg 0402LF  page 14 : A = SVID_DIO1_CPU0_R ; B = PVNN_TERM_CPU0
C1908  Q_CAP  0.01UF 50V 10% X7R  pkg C0402  page 217 : A = P3V3_AUX_FPGA_VCCIO4 ; B = GND

(kicad_pcb
	(version 20260206)
	(generator "pcbnew")
	(generator_version "10.0")
	(general
		(thickness 1.6)
		(legacy_teardrops no)
	)
	(paper "A4")
	(title_block
		(title "03242023_DA0F0TMBIJ0_F0T_Motherboard_J_brd_V01_OCP.brd")
		(comment 1 "Grand Teton / footprints 4495-4496 of 6105")
	)
	(layers
		(0 "F.Cu" signal "TOP")
		(4 "In1.Cu" signal "GND")
		(6 "In2.Cu" signal "IN1")
		(8 "In3.Cu" signal "GND1")
		(10 "In4.Cu" signal "IN2")
		(12 "In5.Cu" signal "GND2")
		(14 "In6.Cu" signal "IN3")
		(16 "In7.Cu" signal "GND3")
		(18 "In8.Cu" signal "VCC")
		(20 "In9.Cu" signal "VCC1")
		(22 "In10.Cu" signal "GND4")
		(24 "In11.Cu" signal "IN4")
		(26 "In12.Cu" signal "GND5")
		(28 "In13.Cu" signal "IN5")
		(30 "In14.Cu" signal "GND6")
		(32 "In15.Cu" signal "IN6")
		(34 "In16.Cu" signal "GND7")
		(2 "B.Cu" signal "BOTTOM")
		(9 "F.Adhes" user "F.Adhesive")
		(11 "B.Adhes" user "B.Adhesive")
		(13 "F.Paste" user "Package Geometry/Pastemask Top")
		(15 "B.Paste" user "Package Geometry/Pastemask Bottom")
		(5 "F.SilkS" user "Ref Des/Silkscreen Top")
		(7 "B.SilkS" user "Ref Des/Silkscreen Bottom")
		(1 "F.Mask" user "Board Geometry/Soldermask Top")
		(3 "B.Mask" user "Board Geometry/Soldermask Bottom")
		(17 "Dwgs.User" user "User.Drawings")
		(19 "Cmts.User" user "User.Comments")
		(21 "Eco1.User" user "User.Eco1")
		(23 "Eco2.User" user "User.Eco2")
		(25 "Edge.Cuts" user "Board Geometry/Outline")
		(27 "Margin" user)
		(31 "F.CrtYd" user "Package Geometry/Place Bound Top")
		(29 "B.CrtYd" user "Package Geometry/Place Bound Bottom")
		(35 "F.Fab" user "Ref Des/Assembly Top")
		(33 "B.Fab" user "Ref Des/Assembly Bottom")
	)
	(footprint ""
		(layer "B.Cu")
		(at 306.968398 -190.45047 90)
		(property "Reference" "R555"
			(at 0 0 90)
			(layer "B.SilkS")
			(hide yes)
			(effects
				(font
					(size 1.27 1.27)
				)
				(justify mirror)
			)
		)
		(property "Value" ""
			(at 0 0 90)
			(layer "B.Fab")
			(effects
				(font
					(size 1.27 1.27)
				)
				(justify mirror)
			)
		)
		(duplicate_pad_numbers_are_jumpers no)
		(fp_line
			(start 0.7874 -0.4064)
			(end -0.7874 -0.4064)
			(stroke
				(width 0.1524)
				(type default)
			)
			(layer "B.SilkS")
		)
		(fp_line
			(start -0.7874 -0.4064)
			(end -0.7874 0.4064)
			(stroke
				(width 0.1524)
				(type default)
			)
			(layer "B.SilkS")
		)
		(fp_line
			(start 0.7874 0.4064)
			(end 0.7874 -0.4064)
			(stroke
				(width 0.1524)
				(type default)
			)
			(layer "B.SilkS")
		)
		(fp_line
			(start -0.7874 0.4064)
			(end 0.7874 0.4064)
			(stroke
				(width 0.1524)
				(type default)
			)
			(layer "B.SilkS")
		)
		(fp_line
			(start 0.67945 -0.305054)
			(end 0.12065 -0.305054)
			(stroke
				(width 0.1)
				(type default)
			)
			(layer "B.Fab")
		)
		(fp_line
			(start 0.12065 -0.305054)
			(end 0.12065 -0.2794)
			(stroke
				(width 0.1)
				(type default)
			)
			(layer "B.Fab")
		)
		(fp_line
			(start -0.12065 -0.3048)
			(end -0.67945 -0.3048)
			(stroke
				(width 0.1)
				(type default)
			)
			(layer "B.Fab")
		)
		(fp_line
			(start -0.67945 -0.3048)
			(end -0.67945 0.3048)
			(stroke
				(width 0.1)
				(type default)
			)
			(layer "B.Fab")
		)
		(fp_line
			(start 0.12065 -0.2794)
			(end -0.12065 -0.2794)
			(stroke
				(width 0.1)
				(type default)
			)
			(layer "B.Fab")
		)
		(fp_line
			(start -0.12065 -0.2794)
			(end -0.12065 -0.3048)
			(stroke
				(width 0.1)
				(type default)
			)
			(layer "B.Fab")
		)
		(fp_line
			(start 0.12065 0.2794)
			(end 0.12065 0.3048)
			(stroke
				(width 0.1)
				(type default)
			)
			(layer "B.Fab")
		)
		(fp_line
			(start -0.120396 0.2794)
			(end 0.12065 0.2794)
			(stroke
				(width 0.1)
				(type default)
			)
			(layer "B.Fab")
		)
		(fp_line
			(start 0.67945 0.3048)
			(end 0.67945 -0.305054)
			(stroke
				(width 0.1)
				(type default)
			)
			(layer "B.Fab")
		)
		(fp_line
			(start 0.12065 0.3048)
			(end 0.67945 0.3048)
			(stroke
				(width 0.1)
				(type default)
			)
			(layer "B.Fab")
		)
		(fp_line
			(start -0.120396 0.3048)
			(end -0.120396 0.2794)
			(stroke
				(width 0.1)
				(type default)
			)
			(layer "B.Fab")
		)
		(fp_line
			(start -0.67945 0.3048)
			(end -0.120396 0.3048)
			(stroke
				(width 0.1)
				(type default)
			)
			(layer "B.Fab")
		)
		(pad "1" smd circle
			(at 0.40005 0 270)
			(size 0 0)
			(layers "B.Cu" "B.Mask" "B.Paste")
			(net "SVID_DIO1_CPU0_R")
		)
		(pad "2" smd circle
			(at -0.40005 0 270)
			(size 0 0)
			(layers "B.Cu" "B.Mask" "B.Paste")
			(net "PVNN_TERM_CPU0")
		)
	)
	(footprint ""
		(layer "B.Cu")
		(at 178.1556 -110.975394 -90)
		(property "Reference" "C1908"
			(at 0 0 90)
			(layer "B.SilkS")
			(hide yes)
			(effects
				(font
					(size 1.27 1.27)
				)
				(justify mirror)
			)
		)
		(property "Value" ""
			(at 0 0 90)
			(layer "B.Fab")
			(effects
				(font
					(size 1.27 1.27)
				)
				(justify mirror)
			)
		)
		(duplicate_pad_numbers_are_jumpers no)
		(fp_line
			(start -0.69215 0.2921)
			(end 0.69215 0.2921)
			(stroke
				(width 0.1524)
				(type default)
			)
			(layer "B.SilkS")
		)
		(fp_line
			(start 0.69215 0.2921)
			(end 0.69215 -0.2921)
			(stroke
				(width 0.1524)
				(type default)
			)
			(layer "B.SilkS")
		)
		(fp_line
			(start -0.69215 -0.2921)
			(end -0.69215 0.2921)
			(stroke
				(width 0.1524)
				(type default)
			)
			(layer "B.SilkS")
		)
		(fp_line
			(start 0.69215 -0.2921)
			(end -0.69215 -0.2921)
			(stroke
				(width 0.1524)
				(type default)
			)
			(layer "B.SilkS")
		)
		(fp_line
			(start -0.51435 0.2794)
			(end 0.51435 0.2794)
			(stroke
				(width 0.1)
				(type default)
			)
			(layer "B.Fab")
		)
		(fp_line
			(start 0.51435 0.2794)
			(end 0.51435 -0.2794)
			(stroke
				(width 0.1)
				(type default)
			)
			(layer "B.Fab")
		)
		(fp_line
			(start -0.51435 -0.2794)
			(end -0.51435 0.2794)
			(stroke
				(width 0.1)
				(type default)
			)
			(layer "B.Fab")
		)
		(fp_line
			(start 0.51435 -0.2794)
			(end -0.51435 -0.2794)
			(stroke
				(width 0.1)
				(type default)
			)
			(layer "B.Fab")
		)
		(pad "1" smd circle
			(at 0.40005 0 90)
			(size 0 0)
			(layers "B.Cu" "B.Mask" "B.Paste")
			(net "P3V3_AUX_FPGA_VCCIO4")
		)
		(pad "2" smd circle
			(at -0.40005 0 90)
			(size 0 0)
			(layers "B.Cu" "B.Mask" "B.Paste")
			(net "GND")
		)
		(zone
			(layer "B.Cu")
			(hatch none 0.5)
			(connect_pads
				(clearance 0)
			)
			(min_thickness 0.25)
			(keepout
				(tracks not_allowed)
				(vias allowed)
				(pads allowed)
				(copperpour not_allowed)
				(footprints allowed)
			)
			(placement
				(enabled no)
				(sheetname "")
			)
			(fill
				(thermal_gap 0.5)
				(thermal_bridge_width 0.5)
				(island_removal_mode 0)
			)
			(polygon
				(pts
					(xy 178.06797 -110.784894) (xy 178.009804 -110.876334) (xy 178.009804 -111.075724) (xy 178.06797 -111.165894)
					(xy 178.24323 -111.165894) (xy 178.30165 -111.075724) (xy 178.30165 -110.876334) (xy 178.243484 -110.784894)
				)
			)
		)
	)
)
